(kicad_pcb
	(version 20260206)
	(generator "pcbnew")
	(generator_version "10.0")
	(general
		(thickness 1.6)
		(legacy_teardrops no)
	)
	(paper "A4")
	(title_block
		(title "01162023_DA0F0TEBIF0_F0T_Expander_BD_F_brd_V02_OCP.brd")
		(comment 1 "Grand Teton / footprints 4635-4640 of 9728")
	)
	(layers
		(0 "F.Cu" signal "TOP")
		(4 "In1.Cu" signal "GND")
		(6 "In2.Cu" signal "VCC")
		(8 "In3.Cu" signal "VCC1")
		(10 "In4.Cu" signal "GND1")
		(12 "In5.Cu" signal "IN1")
		(14 "In6.Cu" signal "GND2")
		(16 "In7.Cu" signal "IN2")
		(18 "In8.Cu" signal "GND3")
		(20 "In9.Cu" signal "IN3")
		(22 "In10.Cu" signal "GND4")
		(24 "In11.Cu" signal "IN4")
		(26 "In12.Cu" signal "GND5")
		(28 "In13.Cu" signal "IN5")
		(30 "In14.Cu" signal "GND6")
		(32 "In15.Cu" signal "IN6")
		(34 "In16.Cu" signal "GND7")
		(2 "B.Cu" signal "BOTTOM")
		(9 "F.Adhes" user "F.Adhesive")
		(11 "B.Adhes" user "B.Adhesive")
		(13 "F.Paste" user "Package Geometry/Pastemask Top")
		(15 "B.Paste" user "Package Geometry/Pastemask Bottom")
		(5 "F.SilkS" user "Ref Des/Silkscreen Top")
		(7 "B.SilkS" user "Ref Des/Silkscreen Bottom")
		(1 "F.Mask" user "Board Geometry/Soldermask Top")
		(3 "B.Mask" user "Board Geometry/Soldermask Bottom")
		(17 "Dwgs.User" user "User.Drawings")
		(19 "Cmts.User" user "User.Comments")
		(21 "Eco1.User" user "User.Eco1")
		(23 "Eco2.User" user "User.Eco2")
		(25 "Edge.Cuts" user "Board Geometry/Outline")
		(27 "Margin" user)
		(31 "F.CrtYd" user "Package Geometry/Place Bound Top")
		(29 "B.CrtYd" user "Package Geometry/Place Bound Bottom")
		(35 "F.Fab" user "Ref Des/Assembly Top")
		(33 "B.Fab" user "Ref Des/Assembly Bottom")
	)
	(footprint ""
		(layer "F.Cu")
		(at 82.947256 -36.686998 90)
		(property "Reference" "C3664"
			(at 0 0 90)
			(layer "F.SilkS")
			(hide yes)
			(effects
				(font
					(size 1.27 1.27)
				)
			)
		)
		(property "Value" ""
			(at 0 0 90)
			(layer "F.Fab")
			(effects
				(font
					(size 1.27 1.27)
				)
			)
		)
		(duplicate_pad_numbers_are_jumpers no)
		(fp_line
			(start 0.7874 -0.4064)
			(end 0.7874 0.4064)
			(stroke
				(width 0.1524)
				(type default)
			)
			(layer "F.SilkS")
		)
		(fp_line
			(start -0.7874 -0.4064)
			(end 0.7874 -0.4064)
			(stroke
				(width 0.1524)
				(type default)
			)
			(layer "F.SilkS")
		)
		(fp_line
			(start 0.7874 0.4064)
			(end -0.7874 0.4064)
			(stroke
				(width 0.1524)
				(type default)
			)
			(layer "F.SilkS")
		)
		(fp_line
			(start -0.7874 0.4064)
			(end -0.7874 -0.4064)
			(stroke
				(width 0.1524)
				(type default)
			)
			(layer "F.SilkS")
		)
		(fp_line
			(start -0.12065 -0.305054)
			(end -0.12065 -0.2794)
			(stroke
				(width 0.1)
				(type default)
			)
			(layer "F.Fab")
		)
		(fp_line
			(start -0.67945 -0.305054)
			(end -0.12065 -0.305054)
			(stroke
				(width 0.1)
				(type default)
			)
			(layer "F.Fab")
		)
		(fp_line
			(start 0.67945 -0.3048)
			(end 0.67945 0.3048)
			(stroke
				(width 0.1)
				(type default)
			)
			(layer "F.Fab")
		)
		(fp_line
			(start 0.12065 -0.3048)
			(end 0.67945 -0.3048)
			(stroke
				(width 0.1)
				(type default)
			)
			(layer "F.Fab")
		)
		(fp_line
			(start 0.12065 -0.2794)
			(end 0.12065 -0.3048)
			(stroke
				(width 0.1)
				(type default)
			)
			(layer "F.Fab")
		)
		(fp_line
			(start -0.12065 -0.2794)
			(end 0.12065 -0.2794)
			(stroke
				(width 0.1)
				(type default)
			)
			(layer "F.Fab")
		)
		(fp_line
			(start 0.120396 0.2794)
			(end -0.12065 0.2794)
			(stroke
				(width 0.1)
				(type default)
			)
			(layer "F.Fab")
		)
		(fp_line
			(start -0.12065 0.2794)
			(end -0.12065 0.3048)
			(stroke
				(width 0.1)
				(type default)
			)
			(layer "F.Fab")
		)
		(fp_line
			(start 0.67945 0.3048)
			(end 0.120396 0.3048)
			(stroke
				(width 0.1)
				(type default)
			)
			(layer "F.Fab")
		)
		(fp_line
			(start 0.120396 0.3048)
			(end 0.120396 0.2794)
			(stroke
				(width 0.1)
				(type default)
			)
			(layer "F.Fab")
		)
		(fp_line
			(start -0.12065 0.3048)
			(end -0.67945 0.3048)
			(stroke
				(width 0.1)
				(type default)
			)
			(layer "F.Fab")
		)
		(fp_line
			(start -0.67945 0.3048)
			(end -0.67945 -0.305054)
			(stroke
				(width 0.1)
				(type default)
			)
			(layer "F.Fab")
		)
		(pad "1" smd circle
			(at -0.40005 0 90)
			(size 0 0)
			(layers "F.Cu" "F.Mask" "F.Paste")
			(net "P3V3_AUX")
		)
		(pad "2" smd circle
			(at 0.40005 0 90)
			(size 0 0)
			(layers "F.Cu" "F.Mask" "F.Paste")
			(net "GND")
		)
	)
	(footprint ""
		(layer "F.Cu")
		(at 52.243736 -44.87291)
		(property "Reference" "R518"
			(at 0 0 0)
			(layer "F.SilkS")
			(hide yes)
			(effects
				(font
					(size 1.27 1.27)
				)
			)
		)
		(property "Value" ""
			(at 0 0 0)
			(layer "F.Fab")
			(effects
				(font
					(size 1.27 1.27)
				)
			)
		)
		(duplicate_pad_numbers_are_jumpers no)
		(fp_line
			(start -0.7874 -0.4064)
			(end 0.7874 -0.4064)
			(stroke
				(width 0.1524)
				(type default)
			)
			(layer "F.SilkS")
		)
		(fp_line
			(start -0.7874 0.4064)
			(end -0.7874 -0.4064)
			(stroke
				(width 0.1524)
				(type default)
			)
			(layer "F.SilkS")
		)
		(fp_line
			(start 0.7874 -0.4064)
			(end 0.7874 0.4064)
			(stroke
				(width 0.1524)
				(type default)
			)
			(layer "F.SilkS")
		)
		(fp_line
			(start 0.7874 0.4064)
			(end -0.7874 0.4064)
			(stroke
				(width 0.1524)
				(type default)
			)
			(layer "F.SilkS")
		)
		(fp_line
			(start -0.67945 -0.305054)
			(end -0.12065 -0.305054)
			(stroke
				(width 0.1)
				(type default)
			)
			(layer "F.Fab")
		)
		(fp_line
			(start -0.67945 0.3048)
			(end -0.67945 -0.305054)
			(stroke
				(width 0.1)
				(type default)
			)
			(layer "F.Fab")
		)
		(fp_line
			(start -0.12065 -0.305054)
			(end -0.12065 -0.2794)
			(stroke
				(width 0.1)
				(type default)
			)
			(layer "F.Fab")
		)
		(fp_line
			(start -0.12065 -0.2794)
			(end 0.12065 -0.2794)
			(stroke
				(width 0.1)
				(type default)
			)
			(layer "F.Fab")
		)
		(fp_line
			(start -0.12065 0.2794)
			(end -0.12065 0.3048)
			(stroke
				(width 0.1)
				(type default)
			)
			(layer "F.Fab")
		)
		(fp_line
			(start -0.12065 0.3048)
			(end -0.67945 0.3048)
			(stroke
				(width 0.1)
				(type default)
			)
			(layer "F.Fab")
		)
		(fp_line
			(start 0.120396 0.2794)
			(end -0.12065 0.2794)
			(stroke
				(width 0.1)
				(type default)
			)
			(layer "F.Fab")
		)
		(fp_line
			(start 0.120396 0.3048)
			(end 0.120396 0.2794)
			(stroke
				(width 0.1)
				(type default)
			)
			(layer "F.Fab")
		)
		(fp_line
			(start 0.12065 -0.3048)
			(end 0.67945 -0.3048)
			(stroke
				(width 0.1)
				(type default)
			)
			(layer "F.Fab")
		)
		(fp_line
			(start 0.12065 -0.2794)
			(end 0.12065 -0.3048)
			(stroke
				(width 0.1)
				(type default)
			)
			(layer "F.Fab")
		)
		(fp_line
			(start 0.67945 -0.3048)
			(end 0.67945 0.3048)
			(stroke
				(width 0.1)
				(type default)
			)
			(layer "F.Fab")
		)
		(fp_line
			(start 0.67945 0.3048)
			(end 0.120396 0.3048)
			(stroke
				(width 0.1)
				(type default)
			)
			(layer "F.Fab")
		)
		(pad "1" smd circle
			(at -0.40005 0)
			(size 0 0)
			(layers "F.Cu" "F.Mask" "F.Paste")
			(net "SSD1_ADC_A0")
		)
		(pad "2" smd circle
			(at 0.40005 0)
			(size 0 0)
			(layers "F.Cu" "F.Mask" "F.Paste")
			(net "P3V3_AUX")
		)
	)
	(footprint ""
		(layer "F.Cu")
		(at 381.403352 -59.571636 90)
		(property "Reference" "PR278"
			(at 0 0 90)
			(layer "F.SilkS")
			(hide yes)
			(effects
				(font
					(size 1.27 1.27)
				)
			)
		)
		(property "Value" ""
			(at 0 0 90)
			(layer "F.Fab")
			(effects
				(font
					(size 1.27 1.27)
				)
			)
		)
		(duplicate_pad_numbers_are_jumpers no)
		(fp_line
			(start 0.7874 -0.4064)
			(end 0.7874 0.4064)
			(stroke
				(width 0.1524)
				(type default)
			)
			(layer "F.SilkS")
		)
		(fp_line
			(start -0.7874 -0.4064)
			(end 0.7874 -0.4064)
			(stroke
				(width 0.1524)
				(type default)
			)
			(layer "F.SilkS")
		)
		(fp_line
			(start 0.7874 0.4064)
			(end -0.7874 0.4064)
			(stroke
				(width 0.1524)
				(type default)
			)
			(layer "F.SilkS")
		)
		(fp_line
			(start -0.7874 0.4064)
			(end -0.7874 -0.4064)
			(stroke
				(width 0.1524)
				(type default)
			)
			(layer "F.SilkS")
		)
		(fp_line
			(start -0.12065 -0.305054)
			(end -0.12065 -0.2794)
			(stroke
				(width 0.1)
				(type default)
			)
			(layer "F.Fab")
		)
		(fp_line
			(start -0.67945 -0.305054)
			(end -0.12065 -0.305054)
			(stroke
				(width 0.1)
				(type default)
			)
			(layer "F.Fab")
		)
		(fp_line
			(start 0.67945 -0.3048)
			(end 0.67945 0.3048)
			(stroke
				(width 0.1)
				(type default)
			)
			(layer "F.Fab")
		)
		(fp_line
			(start 0.12065 -0.3048)
			(end 0.67945 -0.3048)
			(stroke
				(width 0.1)
				(type default)
			)
			(layer "F.Fab")
		)
		(fp_line
			(start 0.12065 -0.2794)
			(end 0.12065 -0.3048)
			(stroke
				(width 0.1)
				(type default)
			)
			(layer "F.Fab")
		)
		(fp_line
			(start -0.12065 -0.2794)
			(end 0.12065 -0.2794)
			(stroke
				(width 0.1)
				(type default)
			)
			(layer "F.Fab")
		)
		(fp_line
			(start 0.120396 0.2794)
			(end -0.12065 0.2794)
			(stroke
				(width 0.1)
				(type default)
			)
			(layer "F.Fab")
		)
		(fp_line
			(start -0.12065 0.2794)
			(end -0.12065 0.3048)
			(stroke
				(width 0.1)
				(type default)
			)
			(layer "F.Fab")
		)
		(fp_line
			(start 0.67945 0.3048)
			(end 0.120396 0.3048)
			(stroke
				(width 0.1)
				(type default)
			)
			(layer "F.Fab")
		)
		(fp_line
			(start 0.120396 0.3048)
			(end 0.120396 0.2794)
			(stroke
				(width 0.1)
				(type default)
			)
			(layer "F.Fab")
		)
		(fp_line
			(start -0.12065 0.3048)
			(end -0.67945 0.3048)
			(stroke
				(width 0.1)
				(type default)
			)
			(layer "F.Fab")
		)
		(fp_line
			(start -0.67945 0.3048)
			(end -0.67945 -0.305054)
			(stroke
				(width 0.1)
				(type default)
			)
			(layer "F.Fab")
		)
		(pad "1" smd circle
			(at -0.40005 0 90)
			(size 0 0)
			(layers "F.Cu" "F.Mask" "F.Paste")
			(net "P3V3_SSD13_OCP")
		)
		(pad "2" smd circle
			(at 0.40005 0 90)
			(size 0 0)
			(layers "F.Cu" "F.Mask" "F.Paste")
			(net "GND")
		)
	)
	(footprint ""
		(layer "F.Cu")
		(at 239.18799 -91.250262 -90)
		(property "Reference" "C2622"
			(at 0 0 270)
			(layer "F.SilkS")
			(hide yes)
			(effects
				(font
					(size 1.27 1.27)
				)
			)
		)
		(property "Value" ""
			(at 0 0 270)
			(layer "F.Fab")
			(effects
				(font
					(size 1.27 1.27)
				)
			)
		)
		(duplicate_pad_numbers_are_jumpers no)
		(fp_line
			(start -0.7874 0.4064)
			(end -0.7874 -0.4064)
			(stroke
				(width 0.1524)
				(type default)
			)
			(layer "F.SilkS")
		)
		(fp_line
			(start 0.7874 0.4064)
			(end -0.7874 0.4064)
			(stroke
				(width 0.1524)
				(type default)
			)
			(layer "F.SilkS")
		)
		(fp_line
			(start -0.7874 -0.4064)
			(end 0.7874 -0.4064)
			(stroke
				(width 0.1524)
				(type default)
			)
			(layer "F.SilkS")
		)
		(fp_line
			(start 0.7874 -0.4064)
			(end 0.7874 0.4064)
			(stroke
				(width 0.1524)
				(type default)
			)
			(layer "F.SilkS")
		)
		(fp_line
			(start -0.67945 0.3048)
			(end -0.67945 -0.305054)
			(stroke
				(width 0.1)
				(type default)
			)
			(layer "F.Fab")
		)
		(fp_line
			(start -0.12065 0.3048)
			(end -0.67945 0.3048)
			(stroke
				(width 0.1)
				(type default)
			)
			(layer "F.Fab")
		)
		(fp_line
			(start 0.120396 0.3048)
			(end 0.120396 0.2794)
			(stroke
				(width 0.1)
				(type default)
			)
			(layer "F.Fab")
		)
		(fp_line
			(start 0.67945 0.3048)
			(end 0.120396 0.3048)
			(stroke
				(width 0.1)
				(type default)
			)
			(layer "F.Fab")
		)
		(fp_line
			(start -0.12065 0.2794)
			(end -0.12065 0.3048)
			(stroke
				(width 0.1)
				(type default)
			)
			(layer "F.Fab")
		)
		(fp_line
			(start 0.120396 0.2794)
			(end -0.12065 0.2794)
			(stroke
				(width 0.1)
				(type default)
			)
			(layer "F.Fab")
		)
		(fp_line
			(start -0.12065 -0.2794)
			(end 0.12065 -0.2794)
			(stroke
				(width 0.1)
				(type default)
			)
			(layer "F.Fab")
		)
		(fp_line
			(start 0.12065 -0.2794)
			(end 0.12065 -0.3048)
			(stroke
				(width 0.1)
				(type default)
			)
			(layer "F.Fab")
		)
		(fp_line
			(start 0.12065 -0.3048)
			(end 0.67945 -0.3048)
			(stroke
				(width 0.1)
				(type default)
			)
			(layer "F.Fab")
		)
		(fp_line
			(start 0.67945 -0.3048)
			(end 0.67945 0.3048)
			(stroke
				(width 0.1)
				(type default)
			)
			(layer "F.Fab")
		)
		(fp_line
			(start -0.67945 -0.305054)
			(end -0.12065 -0.305054)
			(stroke
				(width 0.1)
				(type default)
			)
			(layer "F.Fab")
		)
		(fp_line
			(start -0.12065 -0.305054)
			(end -0.12065 -0.2794)
			(stroke
				(width 0.1)
				(type default)
			)
			(layer "F.Fab")
		)
		(pad "1" smd circle
			(at -0.40005 0 270)
			(size 0 0)
			(layers "F.Cu" "F.Mask" "F.Paste")
			(net "PEX_USB_HUB_XIN")
		)
		(pad "2" smd circle
			(at 0.40005 0 270)
			(size 0 0)
			(layers "F.Cu" "F.Mask" "F.Paste")
			(net "GND")
		)
	)
	(footprint ""
		(layer "F.Cu")
		(at 129.32156 -129.799334 180)
		(property "Reference" "PD4"
			(at 4.20116 2.685796 0)
			(unlocked yes)
			(layer "F.SilkS")
			(effects
				(font
					(size 0.7874 0.5842)
					(thickness 0.1524)
				)
				(justify left)
			)
		)
		(property "Value" ""
			(at 0 0 180)
			(layer "F.Fab")
			(effects
				(font
					(size 1.27 1.27)
				)
			)
		)
		(duplicate_pad_numbers_are_jumpers no)
		(fp_line
			(start 4.240784 1.970024)
			(end 4.240784 -1.970024)
			(stroke
				(width 0.1524)
				(type default)
			)
			(layer "F.SilkS")
		)
		(fp_line
			(start 4.240784 -1.970024)
			(end -3.656584 -1.970024)
			(stroke
				(width 0.1524)
				(type default)
			)
			(layer "F.SilkS")
		)
		(fp_line
			(start -3.656584 1.970024)
			(end 4.240784 1.970024)
			(stroke
				(width 0.1524)
				(type default)
			)
			(layer "F.SilkS")
		)
		(fp_line
			(start -3.656584 -1.970024)
			(end -3.656584 1.970024)
			(stroke
				(width 0.1524)
				(type default)
			)
			(layer "F.SilkS")
		)
		(fp_poly
			(pts
				(xy 3.580384 1.970024) (xy 3.580384 -1.970024) (xy 4.240784 -1.970024) (xy 4.240784 1.970024)
			)
			(stroke
				(width 0)
				(type default)
			)
			(fill yes)
			(layer "F.SilkS")
		)
		(fp_line
			(start 2.3749 1.970024)
			(end 2.3749 -1.970024)
			(stroke
				(width 0.1)
				(type default)
			)
			(layer "F.Fab")
		)
		(fp_line
			(start 2.3749 -1.970024)
			(end -2.3749 -1.970024)
			(stroke
				(width 0.1)
				(type default)
			)
			(layer "F.Fab")
		)
		(fp_line
			(start -2.3749 1.970024)
			(end 2.3749 1.970024)
			(stroke
				(width 0.1)
				(type default)
			)
			(layer "F.Fab")
		)
		(fp_line
			(start -2.3749 -1.970024)
			(end -2.3749 1.970024)
			(stroke
				(width 0.1)
				(type default)
			)
			(layer "F.Fab")
		)
		(fp_text user "-"
			(at 4.1656 -0.23495 180)
			(unlocked yes)
			(layer "F.Fab")
			(effects
				(font
					(size 1.905 1.4224)
					(thickness 0.1524)
				)
				(justify left)
			)
		)
		(fp_text user "+"
			(at -4.9784 -0.23495 180)
			(unlocked yes)
			(layer "F.Fab")
			(effects
				(font
					(size 1.905 1.4224)
					(thickness 0.1524)
				)
				(justify left)
			)
		)
		(pad "A" smd rect
			(at -2.450084 0 180)
			(size 2.159 2.2606)
			(layers "F.Cu" "F.Mask" "F.Paste")
			(net "GND")
		)
		(pad "C" smd rect
			(at 2.450084 0 180)
			(size 2.159 2.2606)
			(layers "F.Cu" "F.Mask" "F.Paste")
			(net "P12V_AUX")
		)
	)
	(footprint ""
		(layer "F.Cu")
		(at 93.621098 -102.880414 90)
		(property "Reference" "C871"
			(at 0 0 90)
			(layer "F.SilkS")
			(hide yes)
			(effects
				(font
					(size 1.27 1.27)
				)
			)
		)
		(property "Value" ""
			(at 0 0 90)
			(layer "F.Fab")
			(effects
				(font
					(size 1.27 1.27)
				)
			)
		)
		(duplicate_pad_numbers_are_jumpers no)
		(fp_line
			(start 0.7874 -0.4064)
			(end 0.7874 0.4064)
			(stroke
				(width 0.1524)
				(type default)
			)
			(layer "F.SilkS")
		)
		(fp_line
			(start -0.7874 -0.4064)
			(end 0.7874 -0.4064)
			(stroke
				(width 0.1524)
				(type default)
			)
			(layer "F.SilkS")
		)
		(fp_line
			(start 0.7874 0.4064)
			(end -0.7874 0.4064)
			(stroke
				(width 0.1524)
				(type default)
			)
			(layer "F.SilkS")
		)
		(fp_line
			(start -0.7874 0.4064)
			(end -0.7874 -0.4064)
			(stroke
				(width 0.1524)
				(type default)
			)
			(layer "F.SilkS")
		)
		(fp_line
			(start -0.12065 -0.305054)
			(end -0.12065 -0.2794)
			(stroke
				(width 0.1)
				(type default)
			)
			(layer "F.Fab")
		)
		(fp_line
			(start -0.67945 -0.305054)
			(end -0.12065 -0.305054)
			(stroke
				(width 0.1)
				(type default)
			)
			(layer "F.Fab")
		)
		(fp_line
			(start 0.67945 -0.3048)
			(end 0.67945 0.3048)
			(stroke
				(width 0.1)
				(type default)
			)
			(layer "F.Fab")
		)
		(fp_line
			(start 0.12065 -0.3048)
			(end 0.67945 -0.3048)
			(stroke
				(width 0.1)
				(type default)
			)
			(layer "F.Fab")
		)
		(fp_line
			(start 0.12065 -0.2794)
			(end 0.12065 -0.3048)
			(stroke
				(width 0.1)
				(type default)
			)
			(layer "F.Fab")
		)
		(fp_line
			(start -0.12065 -0.2794)
			(end 0.12065 -0.2794)
			(stroke
				(width 0.1)
				(type default)
			)
			(layer "F.Fab")
		)
		(fp_line
			(start 0.120396 0.2794)
			(end -0.12065 0.2794)
			(stroke
				(width 0.1)
				(type default)
			)
			(layer "F.Fab")
		)
		(fp_line
			(start -0.12065 0.2794)
			(end -0.12065 0.3048)
			(stroke
				(width 0.1)
				(type default)
			)
			(layer "F.Fab")
		)
		(fp_line
			(start 0.67945 0.3048)
			(end 0.120396 0.3048)
			(stroke
				(width 0.1)
				(type default)
			)
			(layer "F.Fab")
		)
		(fp_line
			(start 0.120396 0.3048)
			(end 0.120396 0.2794)
			(stroke
				(width 0.1)
				(type default)
			)
			(layer "F.Fab")
		)
		(fp_line
			(start -0.12065 0.3048)
			(end -0.67945 0.3048)
			(stroke
				(width 0.1)
				(type default)
			)
			(layer "F.Fab")
		)
		(fp_line
			(start -0.67945 0.3048)
			(end -0.67945 -0.305054)
			(stroke
				(width 0.1)
				(type default)
			)
			(layer "F.Fab")
		)
		(pad "1" smd circle
			(at -0.40005 0 90)
			(size 0 0)
			(layers "F.Cu" "F.Mask" "F.Paste")
			(net "P3V3_AUX")
		)
		(pad "2" smd circle
			(at 0.40005 0 90)
			(size 0 0)
			(layers "F.Cu" "F.Mask" "F.Paste")
			(net "GND")
		)
	)
)
